#ISCELL
  logical_power cad_note *
  *
#ISCELL
  mstr_misc dns *
  *
#ISCELL
  pure_quanta quanta_title_block_c *
  *
#ISCELL
  standard offpage *
  page156_i10
#ISCELL
  logical_power universal_gnd *
  page156_i11
#CELL
  pure_quanta q_cap *
  page156_i12
#ISCELL
  logical_power universal_gnd *
  page156_i19
#CELL
  pure_quanta q_res *
  page156_i24
#ISCELL
  logical_power universal_power *
  page156_i25
#ISCELL
  logical_power universal_gnd *
  page156_i26
#CELL
  pure_quanta q_cap *
  page156_i27
#CELL
  pure_quanta q_res *
  page156_i28
#ISCELL
  logical_power universal_power *
  page156_i29
#ISCELL
  logical_power universal_gnd *
  page156_i30
#CELL
  pure_quanta 74lvc1g07gv *
  page156_i31
#ISCELL
  logical_power universal_gnd *
  page156_i32
#CELL
  pure_quanta q_cap *
  page156_i33
#ISCELL
  logical_power universal_gnd *
  page156_i34
#CELL
  pure_quanta 74lvc1g17gw *
  page156_i35
#ISCELL
  logical_power universal_power *
  page156_i36
#ISCELL
  logical_power universal_power *
  page156_i37
#CELL
  pure_quanta q_res *
  page156_i38
#CELL
  pure_quanta q_res *
  page156_i39
#CELL
  pure_quanta q_res *
  page156_i40
#CELL
  pure_quanta q_res *
  page156_i41
#CELL
  pure_quanta q_res *
  page156_i42
#ISCELL
  logical_power universal_power *
  page156_i43
#CELL
  pure_quanta q_res *
  page156_i44
#ISCELL
  logical_power universal_power *
  page156_i45
#ISCELL
  logical_power universal_gnd *
  page156_i46
#CELL
  pure_quanta q_cap *
  page156_i47
#ISCELL
  standard offpage *
  page156_i48
#ISCELL
  standard offpage *
  page156_i49
#ISCELL
  standard offpage *
  page156_i5
#ISCELL
  standard offpage *
  page156_i50
#ISCELL
  standard offpage *
  page156_i51
#ISCELL
  standard offpage *
  page156_i52
#CELL
  pure_quanta q_res *
  page156_i55
#ISCELL
  standard offpage *
  page156_i58
#CELL
  pure_quanta q_res *
  page156_i59
#CELL
  pure_quanta q_res *
  page156_i6
#ISCELL
  logical_power universal_power *
  page156_i60
#CELL
  pure_quanta 74lvc1g07gv *
  page156_i61
#ISCELL
  logical_power universal_gnd *
  page156_i64
#CELL
  pure_quanta q_cap *
  page156_i65
#ISCELL
  logical_power universal_power *
  page156_i69
#CELL
  pure_quanta q_res *
  page156_i7
#CELL
  pure_quanta q_res *
  page156_i70
#ISCELL
  logical_power universal_gnd *
  page156_i71
#CELL
  pure_quanta q_res *
  page156_i72
#ISCELL
  standard offpage *
  page156_i73
#CELL
  pure_quanta 74lvc1g126se7 *
  page156_i74
#CELL
  pure_quanta q_res *
  page156_i75
#ISCELL
  standard offpage *
  page156_i76
#ISCELL
  standard offpage *
  page156_i77
#ISCELL
  logical_power universal_gnd *
  page156_i78
#CELL
  pure_quanta 74lvc1g126se7 *
  page156_i79
#ISCELL
  logical_power universal_power *
  page156_i8
#ISCELL
  logical_power universal_gnd *
  page156_i80
#CELL
  pure_quanta q_cap *
  page156_i81
#ISCELL
  logical_power universal_power *
  page156_i82
#ISCELL
  standard offpage *
  page156_i83
#ISCELL
  logical_power universal_gnd *
  page156_i84
#ISCELL
  logical_power universal_gnd *
  page156_i86
#ISCELL
  standard offpage *
  page156_i87
#ISCELL
  standard offpage *
  page156_i9
#CELL
  pure_quanta q_res *
  page156_i90
#ISCELL
  standard offpage *
  page156_i91
#CELL
  pure_quanta 74lvc1g66gv *
  page156_i92
